(kicad_pcb
	(version 20260206)
	(generator "pcbnew")
	(generator_version "10.0")
	(general
		(thickness 1.6)
		(legacy_teardrops no)
	)
	(paper "A4")
	(title_block
		(title "Bryce Canyon_SCC_16316-1_OCP.brd")
		(comment 1 "Bryce Canyon / footprints 255-256 of 1561")
	)
	(layers
		(0 "F.Cu" signal "TOP")
		(4 "In1.Cu" signal "L2GND")
		(6 "In2.Cu" signal "L3")
		(8 "In3.Cu" signal "L4VCC")
		(10 "In4.Cu" signal "L5VCC")
		(12 "In5.Cu" signal "L6")
		(14 "In6.Cu" signal "L7GND")
		(2 "B.Cu" signal "BOTTOM")
		(9 "F.Adhes" user "F.Adhesive")
		(11 "B.Adhes" user "B.Adhesive")
		(13 "F.Paste" user "Package Geometry/Pastemask Top")
		(15 "B.Paste" user "Package Geometry/Pastemask Bottom")
		(5 "F.SilkS" user "Ref Des/Silkscreen Top")
		(7 "B.SilkS" user "Ref Des/Silkscreen Bottom")
		(1 "F.Mask" user "Board Geometry/Soldermask Top")
		(3 "B.Mask" user "Board Geometry/Soldermask Bottom")
		(17 "Dwgs.User" user "User.Drawings")
		(19 "Cmts.User" user "User.Comments")
		(21 "Eco1.User" user "User.Eco1")
		(23 "Eco2.User" user "User.Eco2")
		(25 "Edge.Cuts" user "Board Geometry/Outline")
		(27 "Margin" user)
		(31 "F.CrtYd" user "Package Geometry/Place Bound Top")
		(29 "B.CrtYd" user "Package Geometry/Place Bound Bottom")
		(35 "F.Fab" user "Ref Des/Assembly Top")
		(33 "B.Fab" user "Ref Des/Assembly Bottom")
	)
	(footprint ""
		(layer "F.Cu")
		(at 89.803224 -65.314322)
		(property "Reference" "TP164"
			(at 0 0 0)
			(layer "F.SilkS")
			(hide yes)
			(effects
				(font
					(size 1.27 1.27)
				)
			)
		)
		(property "Value" "TPAD28-2-GP"
			(at -0.0127 -1.6637 0)
			(unlocked yes)
			(layer "F.Fab")
			(hide yes)
			(effects
				(font
					(size 1.016 1.016)
					(thickness 0.1524)
				)
			)
		)
		(property "Device Type" "TPAD28"
			(at -0.0127 -3.1877 0)
			(unlocked yes)
			(layer "F.Fab")
			(hide yes)
			(effects
				(font
					(size 1.016 1.016)
					(thickness 0.1524)
				)
			)
		)
		(duplicate_pad_numbers_are_jumpers no)
		(fp_poly
			(pts
				(arc
					(start 0.3556 0)
					(mid -0.3556 0)
					(end 0.3556 0)
				)
			)
			(stroke
				(width 0)
				(type default)
			)
			(fill no)
			(layer "F.CrtYd")
		)
		(fp_poly
			(pts
				(arc
					(start 0.6096 0)
					(mid -0.6096 0)
					(end 0.6096 0)
				)
			)
			(stroke
				(width 0)
				(type default)
			)
			(fill no)
			(layer "F.Fab")
		)
		(pad "1" smd circle
			(at 0 0)
			(size 0.7112 0.7112)
			(layers "F.Cu" "F.Mask" "F.Paste")
			(net "LED47")
		)
	)
	(footprint ""
		(layer "F.Cu")
		(at 149.250908 -35.666934 -78)
		(property "Reference" "VIA18"
			(at 0 0 282)
			(layer "F.SilkS")
			(hide yes)
			(effects
				(font
					(size 1.27 1.27)
				)
			)
		)
		(property "Value" "100OHM-8L-1D6MM-L13-GP"
			(at 3.289333 0.050849 282)
			(unlocked yes)
			(layer "F.Fab")
			(hide yes)
			(effects
				(font
					(size 1.016 1.016)
					(thickness 0.1524)
				)
			)
		)
		(property "Device Type" "VIA-PCIE-4P-409091"
			(at 3.289207 -1.473208 282)
			(unlocked yes)
			(layer "F.Fab")
			(hide yes)
			(effects
				(font
					(size 1.016 1.016)
					(thickness 0.1524)
				)
			)
		)
		(duplicate_pad_numbers_are_jumpers no)
		(fp_poly
			(pts
				(xy -2.044719 -0.457296) (xy 2.04468 -0.457296) (xy 2.044681 0.457104) (xy -2.044719 0.457104)
			)
			(stroke
				(width 0)
				(type default)
			)
			(fill no)
			(layer "F.CrtYd")
		)
		(fp_poly
			(pts
				(xy -2.044719 -0.457296) (xy 2.04468 -0.457296) (xy 2.044681 0.457104) (xy -2.044719 0.457104)
			)
			(stroke
				(width 0)
				(type default)
			)
			(fill no)
			(layer "F.Fab")
		)
		(pad "1" thru_hole circle
			(at -1.5875 0 282)
			(size 0.508 0.508)
			(drill 0.254)
			(layers "*.Cu" "*.Mask")
			(remove_unused_layers no)
			(net "GND")
			(clearance 0.2032)
			(thermal_gap 0.2032)
		)
		(pad "2" thru_hole circle
			(at -0.5715 0.000001 282)
			(size 0.508 0.508)
			(drill 0.254)
			(layers "*.Cu" "*.Mask")
			(remove_unused_layers no)
			(net "PHY_SCC_TO_IOC_C_41_DP")
			(clearance 0.2032)
			(thermal_gap 0.2032)
		)
		(pad "3" thru_hole circle
			(at 0.5715 -0.000001 282)
			(size 0.508 0.508)
			(drill 0.254)
			(layers "*.Cu" "*.Mask")
			(remove_unused_layers no)
			(net "PHY_SCC_TO_IOC_C_41_DN")
			(clearance 0.2032)
			(thermal_gap 0.2032)
		)
		(pad "4" thru_hole circle
			(at 1.5875 0 282)
			(size 0.508 0.508)
			(drill 0.254)
			(layers "*.Cu" "*.Mask")
			(remove_unused_layers no)
			(net "GND")
			(clearance 0.2032)
			(thermal_gap 0.2032)
		)
	)
)
